(kicad_pcb
	(version 20260206)
	(generator "pcbnew")
	(generator_version "10.0")
	(general
		(thickness 1.6)
		(legacy_teardrops no)
	)
	(paper "A4")
	(title_block
		(title "v2-pdb — ms_pdb_v2.brd")
		(comment 1 "Open CloudServer (Microsoft) / footprint 293 of 348 (J26), pads 1-78 of 166")
	)
	(layers
		(0 "F.Cu" signal "TOP")
		(4 "In1.Cu" signal "GND")
		(6 "In2.Cu" signal "IN1")
		(8 "In3.Cu" signal "VCC")
		(10 "In4.Cu" signal "VCC1")
		(12 "In5.Cu" signal "IN2")
		(14 "In6.Cu" signal "GND1")
		(2 "B.Cu" signal "BOTTOM")
		(9 "F.Adhes" user "F.Adhesive")
		(11 "B.Adhes" user "B.Adhesive")
		(13 "F.Paste" user "Package Geometry/Pastemask Top")
		(15 "B.Paste" user "Package Geometry/Pastemask Bottom")
		(5 "F.SilkS" user "Ref Des/Silkscreen Top")
		(7 "B.SilkS" user "Ref Des/Silkscreen Bottom")
		(1 "F.Mask" user "Board Geometry/Soldermask Top")
		(3 "B.Mask" user "Board Geometry/Soldermask Bottom")
		(17 "Dwgs.User" user "User.Drawings")
		(19 "Cmts.User" user "User.Comments")
		(21 "Eco1.User" user "User.Eco1")
		(23 "Eco2.User" user "User.Eco2")
		(25 "Edge.Cuts" user "Board Geometry/Outline")
		(27 "Margin" user)
		(31 "F.CrtYd" user "Package Geometry/Place Bound Top")
		(29 "B.CrtYd" user "Package Geometry/Place Bound Bottom")
		(35 "F.Fab" user "Ref Des/Assembly Top")
		(33 "B.Fab" user "Ref Des/Assembly Bottom")
	)
	(footprint ""
		(layer "F.Cu")
		(at 6.448806 -261.670546)
		(property "Reference" "J26"
			(at 6.660642 8.995918 90)
			(unlocked yes)
			(layer "F.SilkS")
			(effects
				(font
					(size 0.7874 0.5842)
					(thickness 0.1524)
				)
				(justify left)
			)
		)
		(property "Value" ""
			(at 0 0 0)
			(layer "F.Fab")
			(effects
				(font
					(size 1.27 1.27)
				)
			)
		)
		(duplicate_pad_numbers_are_jumpers no)
		(pad "" np_thru_hole circle
			(at -1.249934 11.649964 270)
			(size 2.413 2.413)
			(drill 2.413)
			(layers "*.Cu" "*.Mask")
			(clearance 0.381)
			(thermal_gap 0.381)
		)
		(pad "" np_thru_hole circle
			(at -1.249934 84.799932 270)
			(size 2.413 2.413)
			(drill 2.413)
			(layers "*.Cu" "*.Mask")
			(clearance 0.381)
			(thermal_gap 0.381)
		)
		(pad "A1" thru_hole rect
			(at 0 0 270)
			(size 1.016 1.016)
			(drill 0.7112)
			(layers "*.Cu" "*.Mask")
			(remove_unused_layers no)
			(net "GND")
			(clearance 0.1016)
			(thermal_gap 0.1016)
			(padstack
				(mode front_inner_back)
				(layer "Inner"
					(shape circle)
					(size 1.016 1.016)
					(clearance 0.1016)
				)
				(layer "B.Cu"
					(shape rect)
					(size 1.016 1.016)
					(clearance 0.1016)
				)
			)
		)
		(pad "A2" thru_hole circle
			(at 1.999996 0.999998 270)
			(size 1.016 1.016)
			(drill 0.7112)
			(layers "*.Cu" "*.Mask")
			(remove_unused_layers no)
			(net "T5_BLAD3_EN")
			(clearance 0.1016)
			(thermal_gap 0.1016)
		)
		(pad "A3" thru_hole circle
			(at 0 1.999996 270)
			(size 1.016 1.016)
			(drill 0.7112)
			(layers "*.Cu" "*.Mask")
			(remove_unused_layers no)
			(net "TP_T5_BLAD4_EN")
			(clearance 0.1016)
			(thermal_gap 0.1016)
		)
		(pad "A4" thru_hole circle
			(at 1.999996 2.999994 270)
			(size 1.016 1.016)
			(drill 0.7112)
			(layers "*.Cu" "*.Mask")
			(remove_unused_layers no)
			(net "GND")
			(clearance 0.1016)
			(thermal_gap 0.1016)
		)
		(pad "A5" thru_hole circle
			(at 0 3.999992 270)
			(size 1.016 1.016)
			(drill 0.7112)
			(layers "*.Cu" "*.Mask")
			(remove_unused_layers no)
			(net "T5_BLAD1_RXD")
			(clearance 0.1016)
			(thermal_gap 0.1016)
		)
		(pad "A6" thru_hole circle
			(at 1.999996 4.99999 270)
			(size 1.016 1.016)
			(drill 0.7112)
			(layers "*.Cu" "*.Mask")
			(remove_unused_layers no)
			(net "T5_BLAD1_TXD")
			(clearance 0.1016)
			(thermal_gap 0.1016)
		)
		(pad "A7" thru_hole circle
			(at 0 5.999988 270)
			(size 1.016 1.016)
			(drill 0.7112)
			(layers "*.Cu" "*.Mask")
			(remove_unused_layers no)
			(net "GND")
			(clearance 0.1016)
			(thermal_gap 0.1016)
		)
		(pad "A8" thru_hole circle
			(at 1.999996 6.999986 270)
			(size 1.016 1.016)
			(drill 0.7112)
			(layers "*.Cu" "*.Mask")
			(remove_unused_layers no)
			(net "T5_BLAD2_RXD")
			(clearance 0.1016)
			(thermal_gap 0.1016)
		)
		(pad "A9" thru_hole circle
			(at 0 7.999984 270)
			(size 1.016 1.016)
			(drill 0.7112)
			(layers "*.Cu" "*.Mask")
			(remove_unused_layers no)
			(net "T5_BLAD2_TXD")
			(clearance 0.1016)
			(thermal_gap 0.1016)
		)
		(pad "A10" thru_hole circle
			(at 1.999996 8.999982 270)
			(size 1.016 1.016)
			(drill 0.7112)
			(layers "*.Cu" "*.Mask")
			(remove_unused_layers no)
			(net "T5_BLAD3_RXD")
			(clearance 0.1016)
			(thermal_gap 0.1016)
		)
		(pad "A11" thru_hole circle
			(at 0 9.99998 270)
			(size 1.016 1.016)
			(drill 0.7112)
			(layers "*.Cu" "*.Mask")
			(remove_unused_layers no)
			(net "T5_BLAD3_TXD")
			(clearance 0.1016)
			(thermal_gap 0.1016)
		)
		(pad "A12" thru_hole circle
			(at 1.999996 12.999974 270)
			(size 1.016 1.016)
			(drill 0.7112)
			(layers "*.Cu" "*.Mask")
			(remove_unused_layers no)
			(net "T5_BLAD4_RXD")
			(clearance 0.1016)
			(thermal_gap 0.1016)
		)
		(pad "A13" thru_hole circle
			(at 0 13.999972 270)
			(size 1.016 1.016)
			(drill 0.7112)
			(layers "*.Cu" "*.Mask")
			(remove_unused_layers no)
			(net "T5_BLAD4_TXD")
			(clearance 0.1016)
			(thermal_gap 0.1016)
		)
		(pad "A14" thru_hole circle
			(at 1.999996 14.99997 270)
			(size 1.016 1.016)
			(drill 0.7112)
			(layers "*.Cu" "*.Mask")
			(remove_unused_layers no)
			(net "GND")
			(clearance 0.1016)
			(thermal_gap 0.1016)
		)
		(pad "A15" thru_hole circle
			(at 0 15.999968 270)
			(size 1.016 1.016)
			(drill 0.7112)
			(layers "*.Cu" "*.Mask")
			(remove_unused_layers no)
			(net "T3_BLAD1_EN")
			(clearance 0.1016)
			(thermal_gap 0.1016)
		)
		(pad "A16" thru_hole circle
			(at 1.999996 16.999966 270)
			(size 1.016 1.016)
			(drill 0.7112)
			(layers "*.Cu" "*.Mask")
			(remove_unused_layers no)
			(net "TP_T3_BLAD2_EN")
			(clearance 0.1016)
			(thermal_gap 0.1016)
		)
		(pad "A17" thru_hole circle
			(at 0 17.999964 270)
			(size 1.016 1.016)
			(drill 0.7112)
			(layers "*.Cu" "*.Mask")
			(remove_unused_layers no)
			(net "T3_BLAD3_EN")
			(clearance 0.1016)
			(thermal_gap 0.1016)
		)
		(pad "A18" thru_hole circle
			(at 1.999996 18.999962 270)
			(size 1.016 1.016)
			(drill 0.7112)
			(layers "*.Cu" "*.Mask")
			(remove_unused_layers no)
			(net "TP_T3_BLAD4_EN")
			(clearance 0.1016)
			(thermal_gap 0.1016)
		)
		(pad "A19" thru_hole circle
			(at 0 19.99996 270)
			(size 1.016 1.016)
			(drill 0.7112)
			(layers "*.Cu" "*.Mask")
			(remove_unused_layers no)
			(net "GND")
			(clearance 0.1016)
			(thermal_gap 0.1016)
		)
		(pad "A20" thru_hole circle
			(at 1.999996 20.999958 270)
			(size 1.016 1.016)
			(drill 0.7112)
			(layers "*.Cu" "*.Mask")
			(remove_unused_layers no)
			(net "T3_BLAD1_RXD")
			(clearance 0.1016)
			(thermal_gap 0.1016)
		)
		(pad "A21" thru_hole circle
			(at 0 21.999956 270)
			(size 1.016 1.016)
			(drill 0.7112)
			(layers "*.Cu" "*.Mask")
			(remove_unused_layers no)
			(net "T3_BLAD1_TXD")
			(clearance 0.1016)
			(thermal_gap 0.1016)
		)
		(pad "A22" thru_hole circle
			(at 1.999996 22.999954 270)
			(size 1.016 1.016)
			(drill 0.7112)
			(layers "*.Cu" "*.Mask")
			(remove_unused_layers no)
			(net "T3_BLAD2_RXD")
			(clearance 0.1016)
			(thermal_gap 0.1016)
		)
		(pad "A23" thru_hole circle
			(at 0 23.999952 270)
			(size 1.016 1.016)
			(drill 0.7112)
			(layers "*.Cu" "*.Mask")
			(remove_unused_layers no)
			(net "T3_BLAD2_TXD")
			(clearance 0.1016)
			(thermal_gap 0.1016)
		)
		(pad "A24" thru_hole circle
			(at 1.999996 24.99995 270)
			(size 1.016 1.016)
			(drill 0.7112)
			(layers "*.Cu" "*.Mask")
			(remove_unused_layers no)
			(net "GND")
			(clearance 0.1016)
			(thermal_gap 0.1016)
		)
		(pad "A25" thru_hole circle
			(at 0 25.999948 270)
			(size 1.016 1.016)
			(drill 0.7112)
			(layers "*.Cu" "*.Mask")
			(remove_unused_layers no)
			(net "T3_BLAD3_RXD")
			(clearance 0.1016)
			(thermal_gap 0.1016)
		)
		(pad "A26" thru_hole circle
			(at 1.999996 26.999946 270)
			(size 1.016 1.016)
			(drill 0.7112)
			(layers "*.Cu" "*.Mask")
			(remove_unused_layers no)
			(net "T3_BLAD3_TXD")
			(clearance 0.1016)
			(thermal_gap 0.1016)
		)
		(pad "A27" thru_hole circle
			(at 0 27.999944 270)
			(size 1.016 1.016)
			(drill 0.7112)
			(layers "*.Cu" "*.Mask")
			(remove_unused_layers no)
			(net "T3_BLAD4_RXD")
			(clearance 0.1016)
			(thermal_gap 0.1016)
		)
		(pad "A28" thru_hole circle
			(at 1.999996 28.999942 270)
			(size 1.016 1.016)
			(drill 0.7112)
			(layers "*.Cu" "*.Mask")
			(remove_unused_layers no)
			(net "T3_BLAD4_TXD")
			(clearance 0.1016)
			(thermal_gap 0.1016)
		)
		(pad "A29" thru_hole circle
			(at 0 29.99994 270)
			(size 1.016 1.016)
			(drill 0.7112)
			(layers "*.Cu" "*.Mask")
			(remove_unused_layers no)
			(net "GND")
			(clearance 0.1016)
			(thermal_gap 0.1016)
		)
		(pad "A30" thru_hole circle
			(at 1.999996 30.999938 270)
			(size 1.016 1.016)
			(drill 0.7112)
			(layers "*.Cu" "*.Mask")
			(remove_unused_layers no)
			(net "T1_BLAD1_EN")
			(clearance 0.1016)
			(thermal_gap 0.1016)
		)
		(pad "A31" thru_hole circle
			(at 0 31.999936 270)
			(size 1.016 1.016)
			(drill 0.7112)
			(layers "*.Cu" "*.Mask")
			(remove_unused_layers no)
			(net "T1_BLAD2_EN")
			(clearance 0.1016)
			(thermal_gap 0.1016)
		)
		(pad "A32" thru_hole circle
			(at 1.999996 32.999934 270)
			(size 1.016 1.016)
			(drill 0.7112)
			(layers "*.Cu" "*.Mask")
			(remove_unused_layers no)
			(net "T1_BLAD3_EN")
			(clearance 0.1016)
			(thermal_gap 0.1016)
		)
		(pad "A33" thru_hole circle
			(at 0 33.999932 270)
			(size 1.016 1.016)
			(drill 0.7112)
			(layers "*.Cu" "*.Mask")
			(remove_unused_layers no)
			(net "TP_T1_BLAD4_EN")
			(clearance 0.1016)
			(thermal_gap 0.1016)
		)
		(pad "A34" thru_hole circle
			(at 1.999996 34.99993 270)
			(size 1.016 1.016)
			(drill 0.7112)
			(layers "*.Cu" "*.Mask")
			(remove_unused_layers no)
			(net "GND")
			(clearance 0.1016)
			(thermal_gap 0.1016)
		)
		(pad "A35" thru_hole circle
			(at 0 35.999928 270)
			(size 1.016 1.016)
			(drill 0.7112)
			(layers "*.Cu" "*.Mask")
			(remove_unused_layers no)
			(net "T1_BLAD2_RXD")
			(clearance 0.1016)
			(thermal_gap 0.1016)
		)
		(pad "A36" thru_hole circle
			(at 1.999996 36.999926 270)
			(size 1.016 1.016)
			(drill 0.7112)
			(layers "*.Cu" "*.Mask")
			(remove_unused_layers no)
			(net "T1_BLAD2_TXD")
			(clearance 0.1016)
			(thermal_gap 0.1016)
		)
		(pad "A37" thru_hole circle
			(at 0 37.999924 270)
			(size 1.016 1.016)
			(drill 0.7112)
			(layers "*.Cu" "*.Mask")
			(remove_unused_layers no)
			(net "T1_BLAD3_RXD")
			(clearance 0.1016)
			(thermal_gap 0.1016)
		)
		(pad "A38" thru_hole circle
			(at 1.999996 38.999922 270)
			(size 1.016 1.016)
			(drill 0.7112)
			(layers "*.Cu" "*.Mask")
			(remove_unused_layers no)
			(net "T1_BLAD3_TXD")
			(clearance 0.1016)
			(thermal_gap 0.1016)
		)
		(pad "A39" thru_hole circle
			(at 0 39.99992 270)
			(size 1.016 1.016)
			(drill 0.7112)
			(layers "*.Cu" "*.Mask")
			(remove_unused_layers no)
			(net "GND")
			(clearance 0.1016)
			(thermal_gap 0.1016)
		)
		(pad "A40" thru_hole circle
			(at 1.999996 40.999918 270)
			(size 1.016 1.016)
			(drill 0.7112)
			(layers "*.Cu" "*.Mask")
			(remove_unused_layers no)
			(net "T1_BLAD4_RXD")
			(clearance 0.1016)
			(thermal_gap 0.1016)
		)
		(pad "A41" thru_hole circle
			(at 0 41.999916 270)
			(size 1.016 1.016)
			(drill 0.7112)
			(layers "*.Cu" "*.Mask")
			(remove_unused_layers no)
			(net "T1_BLAD4_TXD")
			(clearance 0.1016)
			(thermal_gap 0.1016)
		)
		(pad "A42" thru_hole circle
			(at 1.999996 42.999914 270)
			(size 1.016 1.016)
			(drill 0.7112)
			(layers "*.Cu" "*.Mask")
			(remove_unused_layers no)
			(net "T1_BLAD1_RXD")
			(clearance 0.1016)
			(thermal_gap 0.1016)
		)
		(pad "A43" thru_hole circle
			(at 0 43.999912 270)
			(size 1.016 1.016)
			(drill 0.7112)
			(layers "*.Cu" "*.Mask")
			(remove_unused_layers no)
			(net "T1_BLAD1_TXD")
			(clearance 0.1016)
			(thermal_gap 0.1016)
		)
		(pad "A44" thru_hole circle
			(at 1.999996 44.99991 270)
			(size 1.016 1.016)
			(drill 0.7112)
			(layers "*.Cu" "*.Mask")
			(remove_unused_layers no)
			(net "GND")
			(clearance 0.1016)
			(thermal_gap 0.1016)
		)
		(pad "A45" thru_hole circle
			(at 0 45.999908 270)
			(size 1.016 1.016)
			(drill 0.7112)
			(layers "*.Cu" "*.Mask")
			(remove_unused_layers no)
			(net "PSU1_DC_OK")
			(clearance 0.1016)
			(thermal_gap 0.1016)
		)
		(pad "A46" thru_hole circle
			(at 1.999996 46.999906 270)
			(size 1.016 1.016)
			(drill 0.7112)
			(layers "*.Cu" "*.Mask")
			(remove_unused_layers no)
			(net "PSU2_DC_OK")
			(clearance 0.1016)
			(thermal_gap 0.1016)
		)
		(pad "A47" thru_hole circle
			(at 0 47.999904 270)
			(size 1.016 1.016)
			(drill 0.7112)
			(layers "*.Cu" "*.Mask")
			(remove_unused_layers no)
			(net "PSU3_DC_OK")
			(clearance 0.1016)
			(thermal_gap 0.1016)
		)
		(pad "A48" thru_hole circle
			(at 1.999996 48.999902 270)
			(size 1.016 1.016)
			(drill 0.7112)
			(layers "*.Cu" "*.Mask")
			(remove_unused_layers no)
			(net "PSU4_DC_OK")
			(clearance 0.1016)
			(thermal_gap 0.1016)
		)
		(pad "A49" thru_hole circle
			(at 0 49.9999 270)
			(size 1.016 1.016)
			(drill 0.7112)
			(layers "*.Cu" "*.Mask")
			(remove_unused_layers no)
			(net "PSU5_DC_OK")
			(clearance 0.1016)
			(thermal_gap 0.1016)
		)
		(pad "A50" thru_hole circle
			(at 1.999996 50.999898 270)
			(size 1.016 1.016)
			(drill 0.7112)
			(layers "*.Cu" "*.Mask")
			(remove_unused_layers no)
			(net "PSU6_DC_OK")
			(clearance 0.1016)
			(thermal_gap 0.1016)
		)
		(pad "A51" thru_hole circle
			(at 0 51.999896 270)
			(size 1.016 1.016)
			(drill 0.7112)
			(layers "*.Cu" "*.Mask")
			(remove_unused_layers no)
			(net "GND")
			(clearance 0.1016)
			(thermal_gap 0.1016)
		)
		(pad "A52" thru_hole circle
			(at 1.999996 52.999894 270)
			(size 1.016 1.016)
			(drill 0.7112)
			(layers "*.Cu" "*.Mask")
			(remove_unused_layers no)
			(net "UART_RTS_P6_L_N")
			(clearance 0.1016)
			(thermal_gap 0.1016)
		)
		(pad "A53" thru_hole circle
			(at 0 53.999892 270)
			(size 1.016 1.016)
			(drill 0.7112)
			(layers "*.Cu" "*.Mask")
			(remove_unused_layers no)
			(net "UART_DSR_P6_L_N")
			(clearance 0.1016)
			(thermal_gap 0.1016)
		)
		(pad "A54" thru_hole circle
			(at 1.999996 54.99989 270)
			(size 1.016 1.016)
			(drill 0.7112)
			(layers "*.Cu" "*.Mask")
			(remove_unused_layers no)
			(net "UART_RX_P6_L")
			(clearance 0.1016)
			(thermal_gap 0.1016)
		)
		(pad "A55" thru_hole circle
			(at 0 55.999888 270)
			(size 1.016 1.016)
			(drill 0.7112)
			(layers "*.Cu" "*.Mask")
			(remove_unused_layers no)
			(net "UART_TX_P6_L")
			(clearance 0.1016)
			(thermal_gap 0.1016)
		)
		(pad "A56" thru_hole circle
			(at 1.999996 56.999886 270)
			(size 1.016 1.016)
			(drill 0.7112)
			(layers "*.Cu" "*.Mask")
			(remove_unused_layers no)
			(net "UART_DTR_P6_L_N")
			(clearance 0.1016)
			(thermal_gap 0.1016)
		)
		(pad "A57" thru_hole circle
			(at 0 57.999884 270)
			(size 1.016 1.016)
			(drill 0.7112)
			(layers "*.Cu" "*.Mask")
			(remove_unused_layers no)
			(net "UART_CTS_P6_L_N")
			(clearance 0.1016)
			(thermal_gap 0.1016)
		)
		(pad "A58" thru_hole circle
			(at 1.999996 59.000136 270)
			(size 1.016 1.016)
			(drill 0.7112)
			(layers "*.Cu" "*.Mask")
			(remove_unused_layers no)
			(net "UART_RI_P6_L_N")
			(clearance 0.1016)
			(thermal_gap 0.1016)
		)
		(pad "A59" thru_hole circle
			(at 0 59.99988 270)
			(size 1.016 1.016)
			(drill 0.7112)
			(layers "*.Cu" "*.Mask")
			(remove_unused_layers no)
			(net "GND")
			(clearance 0.1016)
			(thermal_gap 0.1016)
		)
		(pad "A60" thru_hole circle
			(at 1.999996 61.000132 270)
			(size 1.016 1.016)
			(drill 0.7112)
			(layers "*.Cu" "*.Mask")
			(remove_unused_layers no)
			(net "UART_RTS_P2_L_N")
			(clearance 0.1016)
			(thermal_gap 0.1016)
		)
		(pad "A61" thru_hole circle
			(at 0 61.999876 270)
			(size 1.016 1.016)
			(drill 0.7112)
			(layers "*.Cu" "*.Mask")
			(remove_unused_layers no)
			(net "UART_DSR_P2_L_N")
			(clearance 0.1016)
			(thermal_gap 0.1016)
		)
		(pad "A62" thru_hole circle
			(at 1.999996 63.000128 270)
			(size 1.016 1.016)
			(drill 0.7112)
			(layers "*.Cu" "*.Mask")
			(remove_unused_layers no)
			(net "UART_RX_P2_L")
			(clearance 0.1016)
			(thermal_gap 0.1016)
		)
		(pad "A63" thru_hole circle
			(at 0 63.999872 270)
			(size 1.016 1.016)
			(drill 0.7112)
			(layers "*.Cu" "*.Mask")
			(remove_unused_layers no)
			(net "UART_TX_P2_L")
			(clearance 0.1016)
			(thermal_gap 0.1016)
		)
		(pad "A64" thru_hole circle
			(at 1.999996 65.000124 270)
			(size 1.016 1.016)
			(drill 0.7112)
			(layers "*.Cu" "*.Mask")
			(remove_unused_layers no)
			(net "UART_DTR_P2_L_N")
			(clearance 0.1016)
			(thermal_gap 0.1016)
		)
		(pad "A65" thru_hole circle
			(at 0 65.999868 270)
			(size 1.016 1.016)
			(drill 0.7112)
			(layers "*.Cu" "*.Mask")
			(remove_unused_layers no)
			(net "UART_CTS_P2_L_N")
			(clearance 0.1016)
			(thermal_gap 0.1016)
		)
		(pad "A66" thru_hole circle
			(at 1.999996 67.00012 270)
			(size 1.016 1.016)
			(drill 0.7112)
			(layers "*.Cu" "*.Mask")
			(remove_unused_layers no)
			(net "GND")
			(clearance 0.1016)
			(thermal_gap 0.1016)
		)
		(pad "A67" thru_hole circle
			(at 0 67.999864 270)
			(size 1.016 1.016)
			(drill 0.7112)
			(layers "*.Cu" "*.Mask")
			(remove_unused_layers no)
			(net "Net_431")
			(clearance 0.1016)
			(thermal_gap 0.1016)
		)
		(pad "A68" thru_hole circle
			(at 1.999996 69.000116 270)
			(size 1.016 1.016)
			(drill 0.7112)
			(layers "*.Cu" "*.Mask")
			(remove_unused_layers no)
			(net "Net_435")
			(clearance 0.1016)
			(thermal_gap 0.1016)
		)
		(pad "A69" thru_hole circle
			(at 0 70.000114 270)
			(size 1.016 1.016)
			(drill 0.7112)
			(layers "*.Cu" "*.Mask")
			(remove_unused_layers no)
			(net "Net_434")
			(clearance 0.1016)
			(thermal_gap 0.1016)
		)
		(pad "A70" thru_hole circle
			(at 1.999996 71.000112 270)
			(size 1.016 1.016)
			(drill 0.7112)
			(layers "*.Cu" "*.Mask")
			(remove_unused_layers no)
			(net "GND61")
			(clearance 0.1016)
			(thermal_gap 0.1016)
		)
		(pad "A71" thru_hole circle
			(at 0 72.00011 270)
			(size 1.016 1.016)
			(drill 0.7112)
			(layers "*.Cu" "*.Mask")
			(remove_unused_layers no)
			(net "GND")
			(clearance 0.1016)
			(thermal_gap 0.1016)
		)
		(pad "A72" thru_hole circle
			(at 1.999996 73.000108 270)
			(size 1.016 1.016)
			(drill 0.7112)
			(layers "*.Cu" "*.Mask")
			(remove_unused_layers no)
			(net "LAN1_P1_P")
			(clearance 0.1016)
			(thermal_gap 0.1016)
		)
		(pad "A73" thru_hole circle
			(at 0 74.000106 270)
			(size 1.016 1.016)
			(drill 0.7112)
			(layers "*.Cu" "*.Mask")
			(remove_unused_layers no)
			(net "LAN1_P1_N")
			(clearance 0.1016)
			(thermal_gap 0.1016)
		)
		(pad "A74" thru_hole circle
			(at 1.999996 75.000104 270)
			(size 1.016 1.016)
			(drill 0.7112)
			(layers "*.Cu" "*.Mask")
			(remove_unused_layers no)
			(net "GND")
			(clearance 0.1016)
			(thermal_gap 0.1016)
		)
		(pad "A75" thru_hole circle
			(at 0 76.000102 270)
			(size 1.016 1.016)
			(drill 0.7112)
			(layers "*.Cu" "*.Mask")
			(remove_unused_layers no)
			(net "LAN1_P2_P")
			(clearance 0.1016)
			(thermal_gap 0.1016)
		)
		(pad "A76" thru_hole circle
			(at 1.999996 77.0001 270)
			(size 1.016 1.016)
			(drill 0.7112)
			(layers "*.Cu" "*.Mask")
			(remove_unused_layers no)
			(net "LAN1_P2_N")
			(clearance 0.1016)
			(thermal_gap 0.1016)
		)
	)
)
